# S9S_MB_2U (Grand Teton) — schematic netlist excerpt (pin names and nets, part order shuffled) for the footprints in the layout excerpt that follows; sources: Cadence DE-HDL packaged netlist, KiCad conversion of 03242023_DA0F0TMBIJ0_F0T_Motherboard_J_brd_V01_OCP.brd

R4473  Q_RES  0 5% CHIP  pkg 0402LF  page 196 : A = USB2_0_DP ; B = USB2_HOST_PCH_0_DP
PC1368  Q_CAP  0.1UF 25V 10% X7R  pkg 0402  page 289 : A = GND ; B = PVCCIN_CPU1_VREF

(kicad_pcb
	(version 20260206)
	(generator "pcbnew")
	(generator_version "10.0")
	(general
		(thickness 1.6)
		(legacy_teardrops no)
	)
	(paper "A4")
	(title_block
		(title "03242023_DA0F0TMBIJ0_F0T_Motherboard_J_brd_V01_OCP.brd")
		(comment 1 "Grand Teton / footprints 2594-2595 of 6105")
	)
	(layers
		(0 "F.Cu" signal "TOP")
		(4 "In1.Cu" signal "GND")
		(6 "In2.Cu" signal "IN1")
		(8 "In3.Cu" signal "GND1")
		(10 "In4.Cu" signal "IN2")
		(12 "In5.Cu" signal "GND2")
		(14 "In6.Cu" signal "IN3")
		(16 "In7.Cu" signal "GND3")
		(18 "In8.Cu" signal "VCC")
		(20 "In9.Cu" signal "VCC1")
		(22 "In10.Cu" signal "GND4")
		(24 "In11.Cu" signal "IN4")
		(26 "In12.Cu" signal "GND5")
		(28 "In13.Cu" signal "IN5")
		(30 "In14.Cu" signal "GND6")
		(32 "In15.Cu" signal "IN6")
		(34 "In16.Cu" signal "GND7")
		(2 "B.Cu" signal "BOTTOM")
		(9 "F.Adhes" user "F.Adhesive")
		(11 "B.Adhes" user "B.Adhesive")
		(13 "F.Paste" user "Package Geometry/Pastemask Top")
		(15 "B.Paste" user "Package Geometry/Pastemask Bottom")
		(5 "F.SilkS" user "Ref Des/Silkscreen Top")
		(7 "B.SilkS" user "Ref Des/Silkscreen Bottom")
		(1 "F.Mask" user "Board Geometry/Soldermask Top")
		(3 "B.Mask" user "Board Geometry/Soldermask Bottom")
		(17 "Dwgs.User" user "User.Drawings")
		(19 "Cmts.User" user "User.Comments")
		(21 "Eco1.User" user "User.Eco1")
		(23 "Eco2.User" user "User.Eco2")
		(25 "Edge.Cuts" user "Board Geometry/Outline")
		(27 "Margin" user)
		(31 "F.CrtYd" user "Package Geometry/Place Bound Top")
		(29 "B.CrtYd" user "Package Geometry/Place Bound Bottom")
		(35 "F.Fab" user "Ref Des/Assembly Top")
		(33 "B.Fab" user "Ref Des/Assembly Bottom")
	)
	(footprint ""
		(layer "F.Cu")
		(at 48.501046 -358.129586 -90)
		(property "Reference" "PC1368"
			(at 0 0 270)
			(layer "F.SilkS")
			(hide yes)
			(effects
				(font
					(size 1.27 1.27)
				)
			)
		)
		(property "Value" ""
			(at 0 0 270)
			(layer "F.Fab")
			(effects
				(font
					(size 1.27 1.27)
				)
			)
		)
		(duplicate_pad_numbers_are_jumpers no)
		(fp_line
			(start -0.7874 0.4064)
			(end -0.7874 -0.4064)
			(stroke
				(width 0.1524)
				(type default)
			)
			(layer "F.SilkS")
		)
		(fp_line
			(start 0.7874 0.4064)
			(end -0.7874 0.4064)
			(stroke
				(width 0.1524)
				(type default)
			)
			(layer "F.SilkS")
		)
		(fp_line
			(start -0.7874 -0.4064)
			(end 0.7874 -0.4064)
			(stroke
				(width 0.1524)
				(type default)
			)
			(layer "F.SilkS")
		)
		(fp_line
			(start 0.7874 -0.4064)
			(end 0.7874 0.4064)
			(stroke
				(width 0.1524)
				(type default)
			)
			(layer "F.SilkS")
		)
		(fp_line
			(start -0.67945 0.3048)
			(end -0.67945 -0.305054)
			(stroke
				(width 0.1)
				(type default)
			)
			(layer "F.Fab")
		)
		(fp_line
			(start -0.12065 0.3048)
			(end -0.67945 0.3048)
			(stroke
				(width 0.1)
				(type default)
			)
			(layer "F.Fab")
		)
		(fp_line
			(start 0.120396 0.3048)
			(end 0.120396 0.2794)
			(stroke
				(width 0.1)
				(type default)
			)
			(layer "F.Fab")
		)
		(fp_line
			(start 0.67945 0.3048)
			(end 0.120396 0.3048)
			(stroke
				(width 0.1)
				(type default)
			)
			(layer "F.Fab")
		)
		(fp_line
			(start -0.12065 0.2794)
			(end -0.12065 0.3048)
			(stroke
				(width 0.1)
				(type default)
			)
			(layer "F.Fab")
		)
		(fp_line
			(start 0.120396 0.2794)
			(end -0.12065 0.2794)
			(stroke
				(width 0.1)
				(type default)
			)
			(layer "F.Fab")
		)
		(fp_line
			(start -0.12065 -0.2794)
			(end 0.12065 -0.2794)
			(stroke
				(width 0.1)
				(type default)
			)
			(layer "F.Fab")
		)
		(fp_line
			(start 0.12065 -0.2794)
			(end 0.12065 -0.3048)
			(stroke
				(width 0.1)
				(type default)
			)
			(layer "F.Fab")
		)
		(fp_line
			(start 0.12065 -0.3048)
			(end 0.67945 -0.3048)
			(stroke
				(width 0.1)
				(type default)
			)
			(layer "F.Fab")
		)
		(fp_line
			(start 0.67945 -0.3048)
			(end 0.67945 0.3048)
			(stroke
				(width 0.1)
				(type default)
			)
			(layer "F.Fab")
		)
		(fp_line
			(start -0.67945 -0.305054)
			(end -0.12065 -0.305054)
			(stroke
				(width 0.1)
				(type default)
			)
			(layer "F.Fab")
		)
		(fp_line
			(start -0.12065 -0.305054)
			(end -0.12065 -0.2794)
			(stroke
				(width 0.1)
				(type default)
			)
			(layer "F.Fab")
		)
		(pad "1" smd circle
			(at -0.40005 0 270)
			(size 0 0)
			(layers "F.Cu" "F.Mask" "F.Paste")
			(net "GND")
		)
		(pad "2" smd circle
			(at 0.40005 0 270)
			(size 0 0)
			(layers "F.Cu" "F.Mask" "F.Paste")
			(net "PVCCIN_CPU1_VREF")
		)
	)
	(footprint ""
		(layer "F.Cu")
		(at 158.901384 -44.632626 90)
		(property "Reference" "R4473"
			(at 0 0 90)
			(layer "F.SilkS")
			(hide yes)
			(effects
				(font
					(size 1.27 1.27)
				)
			)
		)
		(property "Value" ""
			(at 0 0 90)
			(layer "F.Fab")
			(effects
				(font
					(size 1.27 1.27)
				)
			)
		)
		(duplicate_pad_numbers_are_jumpers no)
		(fp_line
			(start -0.7874 -0.4064)
			(end 0.7874 -0.4064)
			(stroke
				(width 0.1524)
				(type default)
			)
			(layer "F.SilkS")
		)
		(fp_line
			(start -0.7874 0.4064)
			(end -0.7874 -0.4064)
			(stroke
				(width 0.1524)
				(type default)
			)
			(layer "F.SilkS")
		)
		(fp_line
			(start -0.12065 -0.305054)
			(end -0.12065 -0.2794)
			(stroke
				(width 0.1)
				(type default)
			)
			(layer "F.Fab")
		)
		(fp_line
			(start -0.67945 -0.305054)
			(end -0.12065 -0.305054)
			(stroke
				(width 0.1)
				(type default)
			)
			(layer "F.Fab")
		)
		(fp_line
			(start 0.67945 -0.3048)
			(end 0.67945 0.3048)
			(stroke
				(width 0.1)
				(type default)
			)
			(layer "F.Fab")
		)
		(fp_line
			(start 0.12065 -0.3048)
			(end 0.67945 -0.3048)
			(stroke
				(width 0.1)
				(type default)
			)
			(layer "F.Fab")
		)
		(fp_line
			(start 0.12065 -0.2794)
			(end 0.12065 -0.3048)
			(stroke
				(width 0.1)
				(type default)
			)
			(layer "F.Fab")
		)
		(fp_line
			(start -0.12065 -0.2794)
			(end 0.12065 -0.2794)
			(stroke
				(width 0.1)
				(type default)
			)
			(layer "F.Fab")
		)
		(fp_line
			(start 0.120396 0.2794)
			(end -0.12065 0.2794)
			(stroke
				(width 0.1)
				(type default)
			)
			(layer "F.Fab")
		)
		(fp_line
			(start -0.12065 0.2794)
			(end -0.12065 0.3048)
			(stroke
				(width 0.1)
				(type default)
			)
			(layer "F.Fab")
		)
		(fp_line
			(start 0.67945 0.3048)
			(end 0.120396 0.3048)
			(stroke
				(width 0.1)
				(type default)
			)
			(layer "F.Fab")
		)
		(fp_line
			(start 0.120396 0.3048)
			(end 0.120396 0.2794)
			(stroke
				(width 0.1)
				(type default)
			)
			(layer "F.Fab")
		)
		(fp_line
			(start -0.12065 0.3048)
			(end -0.67945 0.3048)
			(stroke
				(width 0.1)
				(type default)
			)
			(layer "F.Fab")
		)
		(fp_line
			(start -0.67945 0.3048)
			(end -0.67945 -0.305054)
			(stroke
				(width 0.1)
				(type default)
			)
			(layer "F.Fab")
		)
		(pad "1" smd rect
			(at -0.40005 0 270)
			(size 0.4572 0.508)
			(layers "F.Cu" "F.Mask" "F.Paste")
			(net "USB2_0_DP")
		)
		(pad "2" smd rect
			(at 0.40005 0 270)
			(size 0.4572 0.508)
			(layers "F.Cu" "F.Mask" "F.Paste")
			(net "USB2_HOST_PCH_0_DP")
		)
	)
)
